(kicad_pcb
	(version 20260206)
	(generator "pcbnew")
	(generator_version "10.0")
	(general
		(thickness 1.6)
		(legacy_teardrops no)
	)
	(paper "A4")
	(title_block
		(title "Bryce Canyon_SCC_16316-1_OCP.brd")
		(comment 1 "Bryce Canyon / footprints 1331-1337 of 1561")
	)
	(layers
		(0 "F.Cu" signal "TOP")
		(4 "In1.Cu" signal "L2GND")
		(6 "In2.Cu" signal "L3")
		(8 "In3.Cu" signal "L4VCC")
		(10 "In4.Cu" signal "L5VCC")
		(12 "In5.Cu" signal "L6")
		(14 "In6.Cu" signal "L7GND")
		(2 "B.Cu" signal "BOTTOM")
		(9 "F.Adhes" user "F.Adhesive")
		(11 "B.Adhes" user "B.Adhesive")
		(13 "F.Paste" user "Package Geometry/Pastemask Top")
		(15 "B.Paste" user "Package Geometry/Pastemask Bottom")
		(5 "F.SilkS" user "Ref Des/Silkscreen Top")
		(7 "B.SilkS" user "Ref Des/Silkscreen Bottom")
		(1 "F.Mask" user "Board Geometry/Soldermask Top")
		(3 "B.Mask" user "Board Geometry/Soldermask Bottom")
		(17 "Dwgs.User" user "User.Drawings")
		(19 "Cmts.User" user "User.Comments")
		(21 "Eco1.User" user "User.Eco1")
		(23 "Eco2.User" user "User.Eco2")
		(25 "Edge.Cuts" user "Board Geometry/Outline")
		(27 "Margin" user)
		(31 "F.CrtYd" user "Package Geometry/Place Bound Top")
		(29 "B.CrtYd" user "Package Geometry/Place Bound Bottom")
		(35 "F.Fab" user "Ref Des/Assembly Top")
		(33 "B.Fab" user "Ref Des/Assembly Bottom")
	)
	(footprint ""
		(layer "B.Cu")
		(at 174.244 -32.6898 90)
		(property "Reference" "C382"
			(at 0 0 90)
			(layer "B.SilkS")
			(hide yes)
			(effects
				(font
					(size 1.27 1.27)
				)
				(justify mirror)
			)
		)
		(property "Value" "SCD1U16V2KX-3GP"
			(at -1.1811 -2.7051 90)
			(unlocked yes)
			(layer "B.Fab")
			(hide yes)
			(effects
				(font
					(size 1.016 1.016)
					(thickness 0.1524)
				)
				(justify mirror)
			)
		)
		(property "Device Type" "C402H22"
			(at -1.1811 -4.2291 90)
			(unlocked yes)
			(layer "B.Fab")
			(hide yes)
			(effects
				(font
					(size 1.016 1.016)
					(thickness 0.1524)
				)
				(justify mirror)
			)
		)
		(duplicate_pad_numbers_are_jumpers no)
		(fp_rect
			(start 0.4318 0.9525)
			(end -0.4318 -0.9525)
			(stroke
				(width 0)
				(type default)
			)
			(fill no)
			(layer "B.CrtYd")
		)
		(fp_rect
			(start 0.4318 0.9525)
			(end -0.4318 -0.9525)
			(stroke
				(width 0)
				(type default)
			)
			(fill no)
			(layer "B.Fab")
		)
		(pad "1" smd custom
			(at 0 -0.4445 270)
			(size 0.1524 0.1524)
			(layers "B.Cu" "B.Mask" "B.Paste")
			(net "PCE_VDDH")
			(options
				(clearance outline)
				(anchor circle)
			)
			(primitives
				(gr_poly
					(pts
						(arc
							(start 0.3048 0.2032)
							(mid 0.275042 0.275042)
							(end 0.2032 0.3048)
						)
						(arc
							(start -0.2032 0.3048)
							(mid -0.275042 0.275042)
							(end -0.3048 0.2032)
						)
						(arc
							(start -0.3048 -0.2032)
							(mid -0.275042 -0.275042)
							(end -0.2032 -0.3048)
						)
						(arc
							(start 0.2032 -0.3048)
							(mid 0.275042 -0.275042)
							(end 0.3048 -0.2032)
						)
					)
					(width 0)
					(fill yes)
				)
			)
		)
		(pad "2" smd custom
			(at 0 0.4445 270)
			(size 0.1524 0.1524)
			(layers "B.Cu" "B.Mask" "B.Paste")
			(net "GND")
			(options
				(clearance outline)
				(anchor circle)
			)
			(primitives
				(gr_poly
					(pts
						(arc
							(start 0.3048 0.2032)
							(mid 0.275042 0.275042)
							(end 0.2032 0.3048)
						)
						(arc
							(start -0.2032 0.3048)
							(mid -0.275042 0.275042)
							(end -0.3048 0.2032)
						)
						(arc
							(start -0.3048 -0.2032)
							(mid -0.275042 -0.275042)
							(end -0.2032 -0.3048)
						)
						(arc
							(start 0.2032 -0.3048)
							(mid 0.275042 -0.275042)
							(end 0.3048 -0.2032)
						)
					)
					(width 0)
					(fill yes)
				)
			)
		)
	)
	(footprint ""
		(layer "B.Cu")
		(at 76.327 -51.308 180)
		(property "Reference" "C242"
			(at 0 0 0)
			(layer "B.SilkS")
			(hide yes)
			(effects
				(font
					(size 1.27 1.27)
				)
				(justify mirror)
			)
		)
		(property "Value" "SC22U6D3V3MX-9-GP-U"
			(at 0 -2.8194 180)
			(unlocked yes)
			(layer "B.Fab")
			(hide yes)
			(effects
				(font
					(size 1.016 1.016)
					(thickness 0.1524)
				)
				(justify mirror)
			)
		)
		(property "Device Type" "C603H40"
			(at 0 -4.3434 180)
			(unlocked yes)
			(layer "B.Fab")
			(hide yes)
			(effects
				(font
					(size 1.016 1.016)
					(thickness 0.1524)
				)
				(justify mirror)
			)
		)
		(duplicate_pad_numbers_are_jumpers no)
		(fp_line
			(start -0.508 0)
			(end 0.508 0)
			(stroke
				(width 0.2032)
				(type default)
			)
			(layer "B.SilkS")
		)
		(fp_rect
			(start 0.5842 1.3335)
			(end -0.5842 -1.3335)
			(stroke
				(width 0)
				(type default)
			)
			(fill no)
			(layer "B.CrtYd")
		)
		(fp_rect
			(start 0.5842 1.3335)
			(end -0.5842 -1.3335)
			(stroke
				(width 0)
				(type default)
			)
			(fill no)
			(layer "B.Fab")
		)
		(pad "1" smd custom
			(at 0 -0.762)
			(size 0.2159 0.2159)
			(layers "B.Cu" "B.Mask" "B.Paste")
			(net "GB_VDDA")
			(options
				(clearance outline)
				(anchor circle)
			)
			(primitives
				(gr_poly
					(pts
						(arc
							(start -0.3302 0.4318)
							(mid -0.402042 0.402042)
							(end -0.4318 0.3302)
						)
						(arc
							(start -0.4318 -0.3302)
							(mid -0.402042 -0.402042)
							(end -0.3302 -0.4318)
						)
						(arc
							(start 0.3302 -0.4318)
							(mid 0.402042 -0.402042)
							(end 0.4318 -0.3302)
						)
						(arc
							(start 0.4318 0.3302)
							(mid 0.402042 0.402042)
							(end 0.3302 0.4318)
						)
					)
					(width 0)
					(fill yes)
				)
			)
		)
		(pad "2" smd custom
			(at 0 0.762)
			(size 0.2159 0.2159)
			(layers "B.Cu" "B.Mask" "B.Paste")
			(net "GND")
			(options
				(clearance outline)
				(anchor circle)
			)
			(primitives
				(gr_poly
					(pts
						(arc
							(start -0.3302 0.4318)
							(mid -0.402042 0.402042)
							(end -0.4318 0.3302)
						)
						(arc
							(start -0.4318 -0.3302)
							(mid -0.402042 -0.402042)
							(end -0.3302 -0.4318)
						)
						(arc
							(start 0.3302 -0.4318)
							(mid 0.402042 -0.402042)
							(end 0.4318 -0.3302)
						)
						(arc
							(start 0.4318 0.3302)
							(mid 0.402042 0.402042)
							(end 0.3302 0.4318)
						)
					)
					(width 0)
					(fill yes)
				)
			)
		)
	)
	(footprint ""
		(layer "B.Cu")
		(at 172.399706 -63.597536 180)
		(property "Reference" "U16"
			(at 0 0 0)
			(layer "B.SilkS")
			(hide yes)
			(effects
				(font
					(size 1.27 1.27)
				)
				(justify mirror)
			)
		)
		(property "Value" "TPS3808G01DBVT-GP"
			(at 0.0254 -11.9634 180)
			(unlocked yes)
			(layer "B.Fab")
			(hide yes)
			(effects
				(font
					(size 1.016 1.016)
					(thickness 0.1524)
				)
				(justify mirror)
			)
		)
		(property "Device Type" "SOT-6H58"
			(at 0.0254 -13.5636 180)
			(unlocked yes)
			(layer "B.Fab")
			(hide yes)
			(effects
				(font
					(size 1.016 1.016)
					(thickness 0.1524)
				)
				(justify mirror)
			)
		)
		(duplicate_pad_numbers_are_jumpers no)
		(fp_line
			(start 1.9685 0.5842)
			(end 1.9685 2.3622)
			(stroke
				(width 0.508)
				(type default)
			)
			(layer "B.SilkS")
		)
		(fp_line
			(start 1.9685 0.5842)
			(end -1.7145 0.5842)
			(stroke
				(width 0.1524)
				(type default)
			)
			(layer "B.SilkS")
		)
		(fp_line
			(start 1.9685 -0.4064)
			(end 1.5621 0)
			(stroke
				(width 0.1524)
				(type default)
			)
			(layer "B.SilkS")
		)
		(fp_line
			(start 1.9685 -0.5842)
			(end 1.9685 0.5842)
			(stroke
				(width 0.1524)
				(type default)
			)
			(layer "B.SilkS")
		)
		(fp_line
			(start 1.5621 0)
			(end 1.9685 0.4064)
			(stroke
				(width 0.1524)
				(type default)
			)
			(layer "B.SilkS")
		)
		(fp_line
			(start -1.7145 0.5842)
			(end -1.7145 -0.5842)
			(stroke
				(width 0.1524)
				(type default)
			)
			(layer "B.SilkS")
		)
		(fp_line
			(start -1.7145 -0.5842)
			(end 1.9685 -0.5842)
			(stroke
				(width 0.1524)
				(type default)
			)
			(layer "B.SilkS")
		)
		(fp_poly
			(pts
				(xy 1.27 -0.635) (xy -1.27 -0.635) (xy -1.27 0.635) (xy 1.27 0.635)
			)
			(stroke
				(width 0)
				(type default)
			)
			(fill yes)
			(layer "B.SilkS")
		)
		(fp_rect
			(start 1.9685 2.3622)
			(end -1.9685 -2.3622)
			(stroke
				(width 0)
				(type default)
			)
			(fill no)
			(layer "B.CrtYd")
		)
		(fp_poly
			(pts
				(xy 1.9685 -2.3622) (xy -1.9685 -2.3622) (xy -1.9685 2.3622) (xy 1.9685 2.3622)
			)
			(stroke
				(width 0)
				(type default)
			)
			(fill no)
			(layer "B.Fab")
		)
		(pad "1" smd rect
			(at 0.9525 1.3462)
			(size 0.5842 1.016)
			(layers "B.Cu" "B.Mask" "B.Paste")
			(net "IOC_RESET_N")
		)
		(pad "2" smd rect
			(at 0 1.3462)
			(size 0.5842 1.016)
			(layers "B.Cu" "B.Mask" "B.Paste")
			(net "GND")
		)
		(pad "3" smd rect
			(at -0.9525 1.3462)
			(size 0.5842 1.016)
			(layers "B.Cu" "B.Mask" "B.Paste")
			(net "IOC_VREF_SET_LS")
		)
		(pad "4" smd rect
			(at -0.9525 -1.3462)
			(size 0.5842 1.016)
			(layers "B.Cu" "B.Mask" "B.Paste")
			(net "Net_619")
		)
		(pad "5" smd rect
			(at 0 -1.3462)
			(size 0.5842 1.016)
			(layers "B.Cu" "B.Mask" "B.Paste")
			(net "SCC_FULL_PGOOD_SENSE")
		)
		(pad "6" smd rect
			(at 0.9525 -1.3462)
			(size 0.5842 1.016)
			(layers "B.Cu" "B.Mask" "B.Paste")
			(net "P3V3")
		)
	)
	(footprint ""
		(layer "B.Cu")
		(at 120.777 -61.488066)
		(property "Reference" "C219"
			(at 0 0 0)
			(layer "B.SilkS")
			(hide yes)
			(effects
				(font
					(size 1.27 1.27)
				)
				(justify mirror)
			)
		)
		(property "Value" "SCD1U16V2KX-3GP"
			(at -1.1811 -2.7051 0)
			(unlocked yes)
			(layer "B.Fab")
			(hide yes)
			(effects
				(font
					(size 1.016 1.016)
					(thickness 0.1524)
				)
				(justify mirror)
			)
		)
		(property "Device Type" "C402H22"
			(at -1.1811 -4.2291 0)
			(unlocked yes)
			(layer "B.Fab")
			(hide yes)
			(effects
				(font
					(size 1.016 1.016)
					(thickness 0.1524)
				)
				(justify mirror)
			)
		)
		(duplicate_pad_numbers_are_jumpers no)
		(fp_rect
			(start 0.4318 0.9525)
			(end -0.4318 -0.9525)
			(stroke
				(width 0)
				(type default)
			)
			(fill no)
			(layer "B.CrtYd")
		)
		(fp_rect
			(start 0.4318 0.9525)
			(end -0.4318 -0.9525)
			(stroke
				(width 0)
				(type default)
			)
			(fill no)
			(layer "B.Fab")
		)
		(pad "1" smd custom
			(at 0 -0.4445 180)
			(size 0.1524 0.1524)
			(layers "B.Cu" "B.Mask" "B.Paste")
			(net "GB_VDDH")
			(options
				(clearance outline)
				(anchor circle)
			)
			(primitives
				(gr_poly
					(pts
						(arc
							(start 0.3048 0.2032)
							(mid 0.275042 0.275042)
							(end 0.2032 0.3048)
						)
						(arc
							(start -0.2032 0.3048)
							(mid -0.275042 0.275042)
							(end -0.3048 0.2032)
						)
						(arc
							(start -0.3048 -0.2032)
							(mid -0.275042 -0.275042)
							(end -0.2032 -0.3048)
						)
						(arc
							(start 0.2032 -0.3048)
							(mid 0.275042 -0.275042)
							(end 0.3048 -0.2032)
						)
					)
					(width 0)
					(fill yes)
				)
			)
		)
		(pad "2" smd custom
			(at 0 0.4445 180)
			(size 0.1524 0.1524)
			(layers "B.Cu" "B.Mask" "B.Paste")
			(net "GND")
			(options
				(clearance outline)
				(anchor circle)
			)
			(primitives
				(gr_poly
					(pts
						(arc
							(start 0.3048 0.2032)
							(mid 0.275042 0.275042)
							(end 0.2032 0.3048)
						)
						(arc
							(start -0.2032 0.3048)
							(mid -0.275042 0.275042)
							(end -0.3048 0.2032)
						)
						(arc
							(start -0.3048 -0.2032)
							(mid -0.275042 -0.275042)
							(end -0.2032 -0.3048)
						)
						(arc
							(start 0.2032 -0.3048)
							(mid 0.275042 -0.275042)
							(end 0.3048 -0.2032)
						)
					)
					(width 0)
					(fill yes)
				)
			)
		)
	)
	(footprint ""
		(layer "B.Cu")
		(at 115.7986 -86.995)
		(property "Reference" "R393"
			(at 0 0 0)
			(layer "B.SilkS")
			(hide yes)
			(effects
				(font
					(size 1.27 1.27)
				)
				(justify mirror)
			)
		)
		(property "Value" "4K7R2F-GP"
			(at -0.064008 -3.993896 0)
			(unlocked yes)
			(layer "B.Fab")
			(hide yes)
			(effects
				(font
					(size 1.016 1.016)
					(thickness 0.1524)
				)
				(justify mirror)
			)
		)
		(property "Device Type" "R402H16"
			(at -0.064008 -5.517896 0)
			(unlocked yes)
			(layer "B.Fab")
			(hide yes)
			(effects
				(font
					(size 1.016 1.016)
					(thickness 0.1524)
				)
				(justify mirror)
			)
		)
		(duplicate_pad_numbers_are_jumpers no)
		(fp_line
			(start -0.508 -0.9398)
			(end 0.508 -0.9398)
			(stroke
				(width 0.1524)
				(type default)
			)
			(layer "B.SilkS")
		)
		(fp_line
			(start 0.508 -0.9398)
			(end 0.508 0.9398)
			(stroke
				(width 0.1524)
				(type default)
			)
			(layer "B.SilkS")
		)
		(fp_rect
			(start 0.508 0.9398)
			(end -0.508 -0.9398)
			(stroke
				(width 0)
				(type default)
			)
			(fill no)
			(layer "B.CrtYd")
		)
		(fp_rect
			(start 0.508 0.9398)
			(end -0.508 -0.9398)
			(stroke
				(width 0)
				(type default)
			)
			(fill no)
			(layer "B.Fab")
		)
		(pad "1" smd custom
			(at 0 -0.4445 180)
			(size 0.1397 0.1397)
			(layers "B.Cu" "B.Mask" "B.Paste")
			(net "P1V8_E")
			(options
				(clearance outline)
				(anchor circle)
			)
			(primitives
				(gr_poly
					(pts
						(arc
							(start -0.1778 0.2794)
							(mid -0.249642 0.249642)
							(end -0.2794 0.1778)
						)
						(arc
							(start -0.2794 -0.1778)
							(mid -0.249642 -0.249642)
							(end -0.1778 -0.2794)
						)
						(arc
							(start 0.1778 -0.2794)
							(mid 0.249642 -0.249642)
							(end 0.2794 -0.1778)
						)
						(arc
							(start 0.2794 0.1778)
							(mid 0.249642 0.249642)
							(end 0.1778 0.2794)
						)
					)
					(width 0)
					(fill yes)
				)
			)
		)
		(pad "2" smd custom
			(at 0 0.4445 180)
			(size 0.1397 0.1397)
			(layers "B.Cu" "B.Mask" "B.Paste")
			(net "EXP_XM_ADDR_17")
			(options
				(clearance outline)
				(anchor circle)
			)
			(primitives
				(gr_poly
					(pts
						(arc
							(start -0.1778 0.2794)
							(mid -0.249642 0.249642)
							(end -0.2794 0.1778)
						)
						(arc
							(start -0.2794 -0.1778)
							(mid -0.249642 -0.249642)
							(end -0.1778 -0.2794)
						)
						(arc
							(start 0.1778 -0.2794)
							(mid 0.249642 -0.249642)
							(end 0.2794 -0.1778)
						)
						(arc
							(start 0.2794 0.1778)
							(mid 0.249642 0.249642)
							(end 0.1778 0.2794)
						)
					)
					(width 0)
					(fill yes)
				)
			)
		)
	)
	(footprint ""
		(layer "B.Cu")
		(at 121.3866 -59.4487)
		(property "Reference" "C251"
			(at 0 0 0)
			(layer "B.SilkS")
			(hide yes)
			(effects
				(font
					(size 1.27 1.27)
				)
				(justify mirror)
			)
		)
		(property "Value" "SCD1U6D3V1KX-GP"
			(at 2.8321 -1.7399 0)
			(unlocked yes)
			(layer "B.Fab")
			(hide yes)
			(effects
				(font
					(size 1.016 1.016)
					(thickness 0.1524)
				)
				(justify mirror)
			)
		)
		(property "Device Type" "C0201H13"
			(at 2.8321 -3.2639 0)
			(unlocked yes)
			(layer "B.Fab")
			(hide yes)
			(effects
				(font
					(size 1.016 1.016)
					(thickness 0.1524)
				)
				(justify mirror)
			)
		)
		(duplicate_pad_numbers_are_jumpers no)
		(fp_rect
			(start 0.2794 0.6477)
			(end -0.2794 -0.6477)
			(stroke
				(width 0)
				(type default)
			)
			(fill no)
			(layer "B.CrtYd")
		)
		(fp_rect
			(start 0.2794 0.6477)
			(end -0.2794 -0.6477)
			(stroke
				(width 0)
				(type default)
			)
			(fill no)
			(layer "B.Fab")
		)
		(pad "1" smd custom
			(at 0 -0.2794 180)
			(size 0.0762 0.0762)
			(layers "B.Cu" "B.Mask" "B.Paste")
			(net "GB_VDDA")
			(options
				(clearance outline)
				(anchor circle)
			)
			(primitives
				(gr_poly
					(pts
						(arc
							(start 0.1524 0.127)
							(mid 0.137521 0.162921)
							(end 0.1016 0.1778)
						)
						(arc
							(start -0.1016 0.1778)
							(mid -0.137521 0.162921)
							(end -0.1524 0.127)
						)
						(arc
							(start -0.1524 -0.127)
							(mid -0.137521 -0.162921)
							(end -0.1016 -0.1778)
						)
						(arc
							(start 0.1016 -0.1778)
							(mid 0.137521 -0.162921)
							(end 0.1524 -0.127)
						)
					)
					(width 0)
					(fill yes)
				)
			)
		)
		(pad "2" smd custom
			(at 0 0.2794 180)
			(size 0.0762 0.0762)
			(layers "B.Cu" "B.Mask" "B.Paste")
			(net "GND")
			(options
				(clearance outline)
				(anchor circle)
			)
			(primitives
				(gr_poly
					(pts
						(arc
							(start 0.1524 0.127)
							(mid 0.137521 0.162921)
							(end 0.1016 0.1778)
						)
						(arc
							(start -0.1016 0.1778)
							(mid -0.137521 0.162921)
							(end -0.1524 0.127)
						)
						(arc
							(start -0.1524 -0.127)
							(mid -0.137521 -0.162921)
							(end -0.1016 -0.1778)
						)
						(arc
							(start 0.1016 -0.1778)
							(mid 0.137521 -0.162921)
							(end 0.1524 -0.127)
						)
					)
					(width 0)
					(fill yes)
				)
			)
		)
	)
	(footprint ""
		(layer "B.Cu")
		(at 93.6244 -82.55)
		(property "Reference" "U42"
			(at 0 0 0)
			(layer "B.SilkS")
			(hide yes)
			(effects
				(font
					(size 1.27 1.27)
				)
				(justify mirror)
			)
		)
		(property "Value" "SN74LVC1G11DCKR-GP"
			(at -0.0508 -11.5824 0)
			(unlocked yes)
			(layer "B.Fab")
			(hide yes)
			(effects
				(font
					(size 1.016 1.016)
					(thickness 0.1524)
				)
				(justify mirror)
			)
		)
		(property "Device Type" "UMT6H44"
			(at -0.0508 -13.1572 0)
			(unlocked yes)
			(layer "B.Fab")
			(hide yes)
			(effects
				(font
					(size 1.016 1.016)
					(thickness 0.1524)
				)
				(justify mirror)
			)
		)
		(duplicate_pad_numbers_are_jumpers no)
		(fp_line
			(start -1.524 -0.36449)
			(end -1.524 -1.82245)
			(stroke
				(width 0.508)
				(type default)
			)
			(layer "B.SilkS")
		)
		(fp_line
			(start -1.524 -0.36449)
			(end -1.524 0.36449)
			(stroke
				(width 0.1524)
				(type default)
			)
			(layer "B.SilkS")
		)
		(fp_line
			(start -1.524 -0.36449)
			(end -1.45796 -0.36449)
			(stroke
				(width 0.1524)
				(type default)
			)
			(layer "B.SilkS")
		)
		(fp_line
			(start -1.524 0.36449)
			(end 1.27 0.36449)
			(stroke
				(width 0.1524)
				(type default)
			)
			(layer "B.SilkS")
		)
		(fp_line
			(start -1.45796 -0.36449)
			(end -1.09347 0)
			(stroke
				(width 0.1524)
				(type default)
			)
			(layer "B.SilkS")
		)
		(fp_line
			(start -1.09347 0)
			(end -1.45796 0.36449)
			(stroke
				(width 0.1524)
				(type default)
			)
			(layer "B.SilkS")
		)
		(fp_line
			(start 1.27 -0.36449)
			(end -1.524 -0.36449)
			(stroke
				(width 0.1524)
				(type default)
			)
			(layer "B.SilkS")
		)
		(fp_line
			(start 1.27 -0.36449)
			(end 1.27 0.36449)
			(stroke
				(width 0.1524)
				(type default)
			)
			(layer "B.SilkS")
		)
		(fp_poly
			(pts
				(xy 0.65024 0.36449) (xy 0.65024 -0.36449) (xy -0.65024 -0.36449) (xy -0.65024 0.36449)
			)
			(stroke
				(width 0)
				(type default)
			)
			(fill yes)
			(layer "B.SilkS")
		)
		(fp_poly
			(pts
				(xy -1.016 -1.0668) (xy -1.016 1.0668) (xy 1.016 1.0668) (xy 1.016 -1.0668)
			)
			(stroke
				(width 0)
				(type default)
			)
			(fill no)
			(layer "B.CrtYd")
		)
		(fp_poly
			(pts
				(xy 1.524 1.905) (xy -1.524 1.905) (xy -1.524 -1.06426) (xy -1.016 -1.06426) (xy -1.016 1.0668)
				(xy 1.016 1.0668) (xy 1.016 -1.0668) (xy -1.524 -1.0668) (xy -1.524 -1.905) (xy 1.524 -1.905)
			)
			(stroke
				(width 0)
				(type default)
			)
			(fill no)
			(layer "B.CrtYd")
		)
		(fp_poly
			(pts
				(xy 1.524 -1.905) (xy 1.524 1.905) (xy -1.524 1.905) (xy -1.524 -1.905)
			)
			(stroke
				(width 0)
				(type default)
			)
			(fill no)
			(layer "B.Fab")
		)
		(pad "1" smd rect
			(at -0.65024 -1.02489 180)
			(size 0.4064 0.8128)
			(layers "B.Cu" "B.Mask" "B.Paste")
			(net "EXP_RESET_N")
		)
		(pad "2" smd rect
			(at 0 -1.02489 180)
			(size 0.4064 0.8128)
			(layers "B.Cu" "B.Mask" "B.Paste")
			(net "GND")
		)
		(pad "3" smd rect
			(at 0.65024 -1.02489 180)
			(size 0.4064 0.8128)
			(layers "B.Cu" "B.Mask" "B.Paste")
			(net "ICE_RESET_N")
		)
		(pad "4" smd rect
			(at 0.65024 1.02489 180)
			(size 0.4064 0.8128)
			(layers "B.Cu" "B.Mask" "B.Paste")
			(net "EXP_SYS_RST_N")
		)
		(pad "5" smd rect
			(at 0 1.02489 180)
			(size 0.4064 0.8128)
			(layers "B.Cu" "B.Mask" "B.Paste")
			(net "P1V8_E")
		)
		(pad "6" smd rect
			(at -0.65024 1.02489 180)
			(size 0.4064 0.8128)
			(layers "B.Cu" "B.Mask" "B.Paste")
			(net "SCC_RESET_LS_R_N")
		)
	)
)
